(kicad_pcb
	(version 20260206)
	(generator "pcbnew")
	(generator_version "10.0")
	(general
		(thickness 1.6)
		(legacy_teardrops no)
	)
	(paper "A4")
	(title_block
		(title "Bryce Canyon_F.DPB_16315-1-OCP.brd")
		(comment 1 "Bryce Canyon / footprints 275-280 of 2223")
	)
	(layers
		(0 "F.Cu" signal "TOP")
		(4 "In1.Cu" signal "L2GND")
		(6 "In2.Cu" signal "L3")
		(8 "In3.Cu" signal "L4GND")
		(10 "In4.Cu" signal "L5")
		(12 "In5.Cu" signal "L6VCC")
		(14 "In6.Cu" signal "L7VCC")
		(16 "In7.Cu" signal "L8")
		(18 "In8.Cu" signal "L9GND")
		(20 "In9.Cu" signal "L10")
		(22 "In10.Cu" signal "L11GND")
		(2 "B.Cu" signal "BOTTOM")
		(9 "F.Adhes" user "F.Adhesive")
		(11 "B.Adhes" user "B.Adhesive")
		(13 "F.Paste" user "Package Geometry/Pastemask Top")
		(15 "B.Paste" user "Package Geometry/Pastemask Bottom")
		(5 "F.SilkS" user "Ref Des/Silkscreen Top")
		(7 "B.SilkS" user "Ref Des/Silkscreen Bottom")
		(1 "F.Mask" user "Board Geometry/Soldermask Top")
		(3 "B.Mask" user "Board Geometry/Soldermask Bottom")
		(17 "Dwgs.User" user "User.Drawings")
		(19 "Cmts.User" user "User.Comments")
		(21 "Eco1.User" user "User.Eco1")
		(23 "Eco2.User" user "User.Eco2")
		(25 "Edge.Cuts" user "Board Geometry/Outline")
		(27 "Margin" user)
		(31 "F.CrtYd" user "Package Geometry/Place Bound Top")
		(29 "B.CrtYd" user "Package Geometry/Place Bound Bottom")
		(35 "F.Fab" user "Ref Des/Assembly Top")
		(33 "B.Fab" user "Ref Des/Assembly Bottom")
	)
	(footprint ""
		(layer "F.Cu")
		(at 17.800066 -324.39991)
		(property "Reference" "RLED25"
			(at 0 0 0)
			(layer "F.SilkS")
			(hide yes)
			(effects
				(font
					(size 1.27 1.27)
				)
			)
		)
		(property "Value" "LED-BY-19-GP"
			(at -2.132076 1.414018 0)
			(unlocked yes)
			(layer "F.Fab")
			(hide yes)
			(effects
				(font
					(size 1.016 1.016)
					(thickness 0.1524)
				)
			)
		)
		(property "Device Type" "LED-1615-4PH26"
			(at -2.132076 -0.109982 0)
			(unlocked yes)
			(layer "F.Fab")
			(hide yes)
			(effects
				(font
					(size 1.016 1.016)
					(thickness 0.1524)
				)
			)
		)
		(duplicate_pad_numbers_are_jumpers no)
		(fp_line
			(start -1.2954 0.254)
			(end -1.2954 1.6002)
			(stroke
				(width 0.508)
				(type default)
			)
			(layer "F.SilkS")
		)
		(fp_line
			(start -1.2954 1.6002)
			(end 1.2954 1.6002)
			(stroke
				(width 0.508)
				(type default)
			)
			(layer "F.SilkS")
		)
		(fp_line
			(start -1.1176 -1.4224)
			(end 1.1176 -1.4224)
			(stroke
				(width 0.1524)
				(type default)
			)
			(layer "F.SilkS")
		)
		(fp_line
			(start -1.1176 1.4224)
			(end -1.1176 -1.4224)
			(stroke
				(width 0.1524)
				(type default)
			)
			(layer "F.SilkS")
		)
		(fp_line
			(start 1.1176 -1.4224)
			(end 1.1176 1.4224)
			(stroke
				(width 0.1524)
				(type default)
			)
			(layer "F.SilkS")
		)
		(fp_line
			(start 1.1176 1.4224)
			(end -1.1176 1.4224)
			(stroke
				(width 0.1524)
				(type default)
			)
			(layer "F.SilkS")
		)
		(fp_line
			(start 1.2954 1.6002)
			(end 1.2954 0.254)
			(stroke
				(width 0.508)
				(type default)
			)
			(layer "F.SilkS")
		)
		(fp_rect
			(start -0.7493 0.8001)
			(end 0.7493 -0.8001)
			(stroke
				(width 0)
				(type default)
			)
			(fill no)
			(layer "F.CrtYd")
		)
		(fp_poly
			(pts
				(xy -1.3716 1.6764) (xy -1.3716 -1.6764) (xy 1.3716 -1.6764) (xy 1.3716 0.0635) (xy 0.7493 0.0635)
				(xy 0.7493 -0.8001) (xy -0.7493 -0.8001) (xy -0.7493 0.8001) (xy 0.7493 0.8001) (xy 0.7493 0.0762)
				(xy 1.3716 0.0762) (xy 1.3716 1.6764)
			)
			(stroke
				(width 0)
				(type default)
			)
			(fill no)
			(layer "F.CrtYd")
		)
		(fp_rect
			(start -1.3716 1.6764)
			(end 1.3716 -1.6764)
			(stroke
				(width 0)
				(type default)
			)
			(fill no)
			(layer "F.Fab")
		)
		(pad "1" smd rect
			(at 0.50038 -0.73025)
			(size 0.7112 0.8636)
			(layers "F.Cu" "F.Mask" "F.Paste")
			(net "DRV_ACT_24")
		)
		(pad "2" smd rect
			(at -0.50038 -0.73025)
			(size 0.7112 0.8636)
			(layers "F.Cu" "F.Mask" "F.Paste")
			(net "FLT_HDD24")
		)
		(pad "3" smd rect
			(at 0.50038 0.73025)
			(size 0.7112 0.8636)
			(layers "F.Cu" "F.Mask" "F.Paste")
			(net "DRV_ACT_24_N")
		)
		(pad "4" smd rect
			(at -0.50038 0.73025)
			(size 0.7112 0.8636)
			(layers "F.Cu" "F.Mask" "F.Paste")
			(net "FLT_HDD24_N")
		)
	)
	(footprint ""
		(layer "F.Cu")
		(at 431.454052 -177.016918)
		(property "Reference" "Q128"
			(at 0 0 0)
			(layer "F.SilkS")
			(hide yes)
			(effects
				(font
					(size 1.27 1.27)
				)
			)
		)
		(property "Value" "AO4407AL-GP"
			(at -3.707384 -1.5367 0)
			(unlocked yes)
			(layer "F.Fab")
			(hide yes)
			(effects
				(font
					(size 1.016 1.016)
					(thickness 0.1524)
				)
			)
		)
		(property "Device Type" "SOIC8H69"
			(at -3.707384 -3.0607 0)
			(unlocked yes)
			(layer "F.Fab")
			(hide yes)
			(effects
				(font
					(size 1.016 1.016)
					(thickness 0.1524)
				)
			)
		)
		(duplicate_pad_numbers_are_jumpers no)
		(fp_line
			(start -2.7432 -1.4224)
			(end -2.7432 1.4224)
			(stroke
				(width 0.1524)
				(type default)
			)
			(layer "F.SilkS")
		)
		(fp_line
			(start -2.7432 1.4224)
			(end -2.6416 1.4224)
			(stroke
				(width 0.1524)
				(type default)
			)
			(layer "F.SilkS")
		)
		(fp_line
			(start -2.7432 1.4224)
			(end 2.1336 1.4224)
			(stroke
				(width 0.1524)
				(type default)
			)
			(layer "F.SilkS")
		)
		(fp_line
			(start -2.7178 -0.508)
			(end -2.1844 -0.0508)
			(stroke
				(width 0.1524)
				(type default)
			)
			(layer "F.SilkS")
		)
		(fp_line
			(start -2.6289 3.4417)
			(end -2.6289 1.4732)
			(stroke
				(width 0.381)
				(type default)
			)
			(layer "F.SilkS")
		)
		(fp_line
			(start -2.1844 -0.0508)
			(end -2.7178 0.508)
			(stroke
				(width 0.1524)
				(type default)
			)
			(layer "F.SilkS")
		)
		(fp_line
			(start 2.1336 -1.4224)
			(end -2.7432 -1.4224)
			(stroke
				(width 0.1524)
				(type default)
			)
			(layer "F.SilkS")
		)
		(fp_line
			(start 2.1336 1.4224)
			(end 2.1336 -1.4224)
			(stroke
				(width 0.1524)
				(type default)
			)
			(layer "F.SilkS")
		)
		(fp_poly
			(pts
				(xy -2.2098 -1.4224) (xy -2.2098 1.4224) (xy 2.2098 1.4224) (xy 2.2098 -1.4224)
			)
			(stroke
				(width 0)
				(type default)
			)
			(fill yes)
			(layer "F.SilkS")
		)
		(fp_rect
			(start -2.450084 2.999994)
			(end 2.450084 -2.999994)
			(stroke
				(width 0)
				(type default)
			)
			(fill no)
			(layer "F.CrtYd")
		)
		(fp_poly
			(pts
				(xy -2.8194 3.6322) (xy -2.8194 -3.6322) (xy 2.8194 -3.6322) (xy 2.8194 1.18364) (xy 2.450084 1.18364)
				(xy 2.450084 -2.999994) (xy -2.450084 -2.999994) (xy -2.450084 2.999994) (xy 2.450084 2.999994)
				(xy 2.450084 1.18618) (xy 2.8194 1.18618) (xy 2.8194 3.6322)
			)
			(stroke
				(width 0)
				(type default)
			)
			(fill no)
			(layer "F.CrtYd")
		)
		(fp_rect
			(start -2.8194 3.6322)
			(end 2.8194 -3.6322)
			(stroke
				(width 0)
				(type default)
			)
			(fill no)
			(layer "F.Fab")
		)
		(pad "1" smd rect
			(at -1.905 2.54)
			(size 0.635 1.651)
			(layers "F.Cu" "F.Mask" "F.Paste")
			(net "P12V_A")
		)
		(pad "2" smd rect
			(at -0.635 2.54)
			(size 0.635 1.651)
			(layers "F.Cu" "F.Mask" "F.Paste")
			(net "P12V_A")
		)
		(pad "3" smd rect
			(at 0.635 2.54)
			(size 0.635 1.651)
			(layers "F.Cu" "F.Mask" "F.Paste")
			(net "P12V_A")
		)
		(pad "4" smd rect
			(at 1.905 2.54)
			(size 0.635 1.651)
			(layers "F.Cu" "F.Mask" "F.Paste")
			(net "SW_HDD_N21")
		)
		(pad "5" smd rect
			(at 1.905 -2.54)
			(size 0.635 1.651)
			(layers "F.Cu" "F.Mask" "F.Paste")
			(net "P12V_HDD21")
		)
		(pad "6" smd rect
			(at 0.635 -2.54)
			(size 0.635 1.651)
			(layers "F.Cu" "F.Mask" "F.Paste")
			(net "P12V_HDD21")
		)
		(pad "7" smd rect
			(at -0.635 -2.54)
			(size 0.635 1.651)
			(layers "F.Cu" "F.Mask" "F.Paste")
			(net "P12V_HDD21")
		)
		(pad "8" smd rect
			(at -1.905 -2.54)
			(size 0.635 1.651)
			(layers "F.Cu" "F.Mask" "F.Paste")
			(net "P12V_HDD21")
		)
	)
	(footprint ""
		(layer "F.Cu")
		(at 262.141462 10.22985 180)
		(property "Reference" "C43"
			(at 0 0 180)
			(layer "F.SilkS")
			(hide yes)
			(effects
				(font
					(size 1.27 1.27)
				)
			)
		)
		(property "Value" "SCD1U16V2KX-3GP"
			(at 1.1811 -2.7051 180)
			(unlocked yes)
			(layer "F.Fab")
			(hide yes)
			(effects
				(font
					(size 1.016 1.016)
					(thickness 0.1524)
				)
			)
		)
		(property "Device Type" "C402H22"
			(at 1.1811 -4.2291 180)
			(unlocked yes)
			(layer "F.Fab")
			(hide yes)
			(effects
				(font
					(size 1.016 1.016)
					(thickness 0.1524)
				)
			)
		)
		(duplicate_pad_numbers_are_jumpers no)
		(fp_rect
			(start -0.4318 0.9525)
			(end 0.4318 -0.9525)
			(stroke
				(width 0)
				(type default)
			)
			(fill no)
			(layer "F.CrtYd")
		)
		(fp_rect
			(start -0.4318 0.9525)
			(end 0.4318 -0.9525)
			(stroke
				(width 0)
				(type default)
			)
			(fill no)
			(layer "F.Fab")
		)
		(pad "1" smd custom
			(at 0 -0.4445 180)
			(size 0.1524 0.1524)
			(layers "F.Cu" "F.Mask" "F.Paste")
			(net "P5V_A_2")
			(options
				(clearance outline)
				(anchor circle)
			)
			(primitives
				(gr_poly
					(pts
						(arc
							(start 0.3048 -0.2032)
							(mid 0.275042 -0.275042)
							(end 0.2032 -0.3048)
						)
						(arc
							(start -0.2032 -0.3048)
							(mid -0.275042 -0.275042)
							(end -0.3048 -0.2032)
						)
						(arc
							(start -0.3048 0.2032)
							(mid -0.275042 0.275042)
							(end -0.2032 0.3048)
						)
						(arc
							(start 0.2032 0.3048)
							(mid 0.275042 0.275042)
							(end 0.3048 0.2032)
						)
					)
					(width 0)
					(fill yes)
				)
			)
		)
		(pad "2" smd custom
			(at 0 0.4445 180)
			(size 0.1524 0.1524)
			(layers "F.Cu" "F.Mask" "F.Paste")
			(net "GND")
			(options
				(clearance outline)
				(anchor circle)
			)
			(primitives
				(gr_poly
					(pts
						(arc
							(start 0.3048 -0.2032)
							(mid 0.275042 -0.275042)
							(end 0.2032 -0.3048)
						)
						(arc
							(start -0.2032 -0.3048)
							(mid -0.275042 -0.275042)
							(end -0.3048 -0.2032)
						)
						(arc
							(start -0.3048 0.2032)
							(mid -0.275042 0.275042)
							(end -0.2032 0.3048)
						)
						(arc
							(start 0.2032 0.3048)
							(mid 0.275042 0.275042)
							(end 0.3048 0.2032)
						)
					)
					(width 0)
					(fill yes)
				)
			)
		)
	)
	(footprint ""
		(layer "F.Cu")
		(at 479.340926 -74.462894 180)
		(property "Reference" "C502"
			(at 0 0 180)
			(layer "F.SilkS")
			(hide yes)
			(effects
				(font
					(size 1.27 1.27)
				)
			)
		)
		(property "Value" "SC1U25V3KX-GP"
			(at 0 -2.8194 180)
			(unlocked yes)
			(layer "F.Fab")
			(hide yes)
			(effects
				(font
					(size 1.016 1.016)
					(thickness 0.1524)
				)
			)
		)
		(property "Device Type" "C603H36"
			(at 0 -4.3434 180)
			(unlocked yes)
			(layer "F.Fab")
			(hide yes)
			(effects
				(font
					(size 1.016 1.016)
					(thickness 0.1524)
				)
			)
		)
		(duplicate_pad_numbers_are_jumpers no)
		(fp_line
			(start 0.508 0)
			(end -0.508 0)
			(stroke
				(width 0.2032)
				(type default)
			)
			(layer "F.SilkS")
		)
		(fp_rect
			(start -0.5842 1.3335)
			(end 0.5842 -1.3335)
			(stroke
				(width 0)
				(type default)
			)
			(fill no)
			(layer "F.CrtYd")
		)
		(fp_rect
			(start -0.5842 1.3335)
			(end 0.5842 -1.3335)
			(stroke
				(width 0)
				(type default)
			)
			(fill no)
			(layer "F.Fab")
		)
		(pad "1" smd custom
			(at 0 -0.762 180)
			(size 0.2159 0.2159)
			(layers "F.Cu" "F.Mask" "F.Paste")
			(net "P12V_HDD35")
			(options
				(clearance outline)
				(anchor circle)
			)
			(primitives
				(gr_poly
					(pts
						(arc
							(start -0.3302 -0.4318)
							(mid -0.402042 -0.402042)
							(end -0.4318 -0.3302)
						)
						(arc
							(start -0.4318 0.3302)
							(mid -0.402042 0.402042)
							(end -0.3302 0.4318)
						)
						(arc
							(start 0.3302 0.4318)
							(mid 0.402042 0.402042)
							(end 0.4318 0.3302)
						)
						(arc
							(start 0.4318 -0.3302)
							(mid 0.402042 -0.402042)
							(end 0.3302 -0.4318)
						)
					)
					(width 0)
					(fill yes)
				)
			)
		)
		(pad "2" smd custom
			(at 0 0.762 180)
			(size 0.2159 0.2159)
			(layers "F.Cu" "F.Mask" "F.Paste")
			(net "GND")
			(options
				(clearance outline)
				(anchor circle)
			)
			(primitives
				(gr_poly
					(pts
						(arc
							(start -0.3302 -0.4318)
							(mid -0.402042 -0.402042)
							(end -0.4318 -0.3302)
						)
						(arc
							(start -0.4318 0.3302)
							(mid -0.402042 0.402042)
							(end -0.3302 0.4318)
						)
						(arc
							(start 0.3302 0.4318)
							(mid 0.402042 0.402042)
							(end 0.4318 0.3302)
						)
						(arc
							(start 0.4318 -0.3302)
							(mid 0.402042 -0.402042)
							(end 0.3302 -0.4318)
						)
					)
					(width 0)
					(fill yes)
				)
			)
		)
	)
	(footprint ""
		(layer "F.Cu")
		(at 419.389052 -162.749992 -90)
		(property "Reference" "VIA25"
			(at 0 0 270)
			(layer "F.SilkS")
			(hide yes)
			(effects
				(font
					(size 1.27 1.27)
				)
			)
		)
		(property "Value" "100OHM-8L-1D6MM-L18L16-GP"
			(at -3.7211 -4.5085 270)
			(unlocked yes)
			(layer "F.Fab")
			(hide yes)
			(effects
				(font
					(size 1.016 1.016)
					(thickness 0.1524)
				)
			)
		)
		(property "Device Type" "VIA-PCIE-4P-394076"
			(at -3.7211 -6.0325 270)
			(unlocked yes)
			(layer "F.Fab")
			(hide yes)
			(effects
				(font
					(size 1.016 1.016)
					(thickness 0.1524)
				)
			)
		)
		(duplicate_pad_numbers_are_jumpers no)
		(fp_rect
			(start -1.9685 0.381)
			(end 1.9685 -0.381)
			(stroke
				(width 0)
				(type default)
			)
			(fill no)
			(layer "F.CrtYd")
		)
		(fp_rect
			(start -1.9685 0.381)
			(end 1.9685 -0.381)
			(stroke
				(width 0)
				(type default)
			)
			(fill no)
			(layer "F.Fab")
		)
		(pad "1" thru_hole circle
			(at -1.5875 0 270)
			(size 0.508 0.508)
			(drill 0.254)
			(layers "*.Cu" "*.Mask")
			(remove_unused_layers no)
			(net "GND")
			(clearance 0.127)
			(thermal_gap 0.127)
		)
		(pad "2" thru_hole circle
			(at -0.5715 0 270)
			(size 0.508 0.508)
			(drill 0.254)
			(layers "*.Cu" "*.Mask")
			(remove_unused_layers no)
			(net "PHY_DRV_A_TO_SCC_A_21_DP")
			(clearance 0.127)
			(thermal_gap 0.127)
		)
		(pad "3" thru_hole circle
			(at 0.5715 0 270)
			(size 0.508 0.508)
			(drill 0.254)
			(layers "*.Cu" "*.Mask")
			(remove_unused_layers no)
			(net "PHY_DRV_A_TO_SCC_A_21_DN")
			(clearance 0.127)
			(thermal_gap 0.127)
		)
		(pad "4" thru_hole circle
			(at 1.5875 0 270)
			(size 0.508 0.508)
			(drill 0.254)
			(layers "*.Cu" "*.Mask")
			(remove_unused_layers no)
			(net "GND")
			(clearance 0.127)
			(thermal_gap 0.127)
		)
	)
	(footprint ""
		(layer "F.Cu")
		(at 395.369542 -283.25445 180)
		(property "Reference" "Q48"
			(at 0 0 180)
			(layer "F.SilkS")
			(hide yes)
			(effects
				(font
					(size 1.27 1.27)
				)
			)
		)
		(property "Value" "AO4406AL-GP"
			(at -3.707384 -1.5367 180)
			(unlocked yes)
			(layer "F.Fab")
			(hide yes)
			(effects
				(font
					(size 1.016 1.016)
					(thickness 0.1524)
				)
			)
		)
		(property "Device Type" "SOIC8H69"
			(at -3.707384 -3.0607 180)
			(unlocked yes)
			(layer "F.Fab")
			(hide yes)
			(effects
				(font
					(size 1.016 1.016)
					(thickness 0.1524)
				)
			)
		)
		(duplicate_pad_numbers_are_jumpers no)
		(fp_line
			(start 2.1336 1.4224)
			(end 2.1336 -1.4224)
			(stroke
				(width 0.1524)
				(type default)
			)
			(layer "F.SilkS")
		)
		(fp_line
			(start 2.1336 -1.4224)
			(end -2.7432 -1.4224)
			(stroke
				(width 0.1524)
				(type default)
			)
			(layer "F.SilkS")
		)
		(fp_line
			(start -2.1844 -0.0508)
			(end -2.7178 0.508)
			(stroke
				(width 0.1524)
				(type default)
			)
			(layer "F.SilkS")
		)
		(fp_line
			(start -2.6289 3.4417)
			(end -2.6289 1.4732)
			(stroke
				(width 0.381)
				(type default)
			)
			(layer "F.SilkS")
		)
		(fp_line
			(start -2.7178 -0.508)
			(end -2.1844 -0.0508)
			(stroke
				(width 0.1524)
				(type default)
			)
			(layer "F.SilkS")
		)
		(fp_line
			(start -2.7432 1.4224)
			(end 2.1336 1.4224)
			(stroke
				(width 0.1524)
				(type default)
			)
			(layer "F.SilkS")
		)
		(fp_line
			(start -2.7432 1.4224)
			(end -2.6416 1.4224)
			(stroke
				(width 0.1524)
				(type default)
			)
			(layer "F.SilkS")
		)
		(fp_line
			(start -2.7432 -1.4224)
			(end -2.7432 1.4224)
			(stroke
				(width 0.1524)
				(type default)
			)
			(layer "F.SilkS")
		)
		(fp_poly
			(pts
				(xy -2.2098 -1.4224) (xy -2.2098 1.4224) (xy 2.2098 1.4224) (xy 2.2098 -1.4224)
			)
			(stroke
				(width 0)
				(type default)
			)
			(fill yes)
			(layer "F.SilkS")
		)
		(fp_rect
			(start -2.450084 2.999994)
			(end 2.450084 -2.999994)
			(stroke
				(width 0)
				(type default)
			)
			(fill no)
			(layer "F.CrtYd")
		)
		(fp_poly
			(pts
				(xy -2.8194 3.6322) (xy -2.8194 -3.6322) (xy 2.8194 -3.6322) (xy 2.8194 1.18364) (xy 2.450084 1.18364)
				(xy 2.450084 -2.999994) (xy -2.450084 -2.999994) (xy -2.450084 2.999994) (xy 2.450084 2.999994)
				(xy 2.450084 1.18618) (xy 2.8194 1.18618) (xy 2.8194 3.6322)
			)
			(stroke
				(width 0)
				(type default)
			)
			(fill no)
			(layer "F.CrtYd")
		)
		(fp_rect
			(start -2.8194 3.6322)
			(end 2.8194 -3.6322)
			(stroke
				(width 0)
				(type default)
			)
			(fill no)
			(layer "F.Fab")
		)
		(pad "1" smd rect
			(at -1.905 2.54 180)
			(size 0.635 1.651)
			(layers "F.Cu" "F.Mask" "F.Paste")
			(net "P5V_HDD8")
		)
		(pad "2" smd rect
			(at -0.635 2.54 180)
			(size 0.635 1.651)
			(layers "F.Cu" "F.Mask" "F.Paste")
			(net "P5V_HDD8")
		)
		(pad "3" smd rect
			(at 0.635 2.54 180)
			(size 0.635 1.651)
			(layers "F.Cu" "F.Mask" "F.Paste")
			(net "P5V_HDD8")
		)
		(pad "4" smd rect
			(at 1.905 2.54 180)
			(size 0.635 1.651)
			(layers "F.Cu" "F.Mask" "F.Paste")
			(net "SW_HDD_P8")
		)
		(pad "5" smd rect
			(at 1.905 -2.54 180)
			(size 0.635 1.651)
			(layers "F.Cu" "F.Mask" "F.Paste")
			(net "P5V_A_3")
		)
		(pad "6" smd rect
			(at 0.635 -2.54 180)
			(size 0.635 1.651)
			(layers "F.Cu" "F.Mask" "F.Paste")
			(net "P5V_A_3")
		)
		(pad "7" smd rect
			(at -0.635 -2.54 180)
			(size 0.635 1.651)
			(layers "F.Cu" "F.Mask" "F.Paste")
			(net "P5V_A_3")
		)
		(pad "8" smd rect
			(at -1.905 -2.54 180)
			(size 0.635 1.651)
			(layers "F.Cu" "F.Mask" "F.Paste")
			(net "P5V_A_3")
		)
	)
)
